G04 ================== begin FILE IDENTIFICATION RECORD ==================*
G04 Layout Name:  16368-sb.brd*
G04 Film Name:    L6*
G04 File Format:  Gerber RS274X*
G04 File Origin:  Cadence Allegro 16.5-S056*
G04 Origin Date:  Tue Feb 07 09:07:45 2017*
G04 *
G04 Layer:  VIA CLASS/BOTTOM*
G04 Layer:  PIN/BOTTOM*
G04 Layer:  ETCH/BOTTOM*
G04 Layer:  DRAWING FORMAT/LAYER_PCB_STORY*
G04 Layer:  DRAWING FORMAT/LAYER_L6*
G04 *
G04 Offset:    (0.00 0.00)*
G04 Mirror:    No*
G04 Mode:      Positive*
G04 Rotation:  0*
G04 FullContactRelief:  No*
G04 UndefLineWidth:     6.00*
G04 ================== end FILE IDENTIFICATION RECORD ====================*
%FSLAX35Y35*MOIN*%
%IR0*IPPOS*OFA0.00000B0.00000*MIA0B0*SFA1.00000B1.00000*%
%AMMACRO19*
4,1,40,.011,.007,
.011,-.007,
.010939,-.007695,
.010759,-.008368,
.010464,-.009,
.010064,-.009571,
.009571,-.010064,
.009,-.010464,
.008368,-.010759,
.007695,-.010939,
.007,-.011,
-.007,-.011,
-.007695,-.010939,
-.008368,-.010759,
-.009,-.010464,
-.009571,-.010064,
-.010064,-.009571,
-.010464,-.009,
-.010759,-.008368,
-.010939,-.007695,
-.011,-.007,
-.011,.007,
-.010939,.007695,
-.010759,.008368,
-.010464,.009,
-.010064,.009571,
-.009571,.010064,
-.009,.010464,
-.008368,.010759,
-.007695,.010939,
-.007,.011,
.007,.011,
.007695,.010939,
.008368,.010759,
.009,.010464,
.009571,.010064,
.010064,.009571,
.010464,.009,
.010759,.008368,
.010939,.007695,
.011,.007,
0.0*
%
%ADD19MACRO19*%
%ADD11C,.01*%
%ADD14C,.02*%
%ADD26C,.022*%
%ADD10C,.04*%
%ADD27C,.024*%
%ADD13C,.042*%
%ADD12C,.034*%
%ADD15R,.039X.108*%
%AMMACRO28*
4,1,40,-.011,-.007,
-.011,.007,
-.010939,.007695,
-.010759,.008368,
-.010464,.009,
-.010064,.009571,
-.009571,.010064,
-.009,.010464,
-.008368,.010759,
-.007695,.010939,
-.007,.011,
.007,.011,
.007695,.010939,
.008368,.010759,
.009,.010464,
.009571,.010064,
.010064,.009571,
.010464,.009,
.010759,.008368,
.010939,.007695,
.011,.007,
.011,-.007,
.010939,-.007695,
.010759,-.008368,
.010464,-.009,
.010064,-.009571,
.009571,-.010064,
.009,-.010464,
.008368,-.010759,
.007695,-.010939,
.007,-.011,
-.007,-.011,
-.007695,-.010939,
-.008368,-.010759,
-.009,-.010464,
-.009571,-.010064,
-.010064,-.009571,
-.010464,-.009,
-.010759,-.008368,
-.010939,-.007695,
-.011,-.007,
0.0*
%
%ADD28MACRO28*%
%AMMACRO16*
4,1,40,.007,-.011,
-.007,-.011,
-.007695,-.010939,
-.008368,-.010759,
-.009,-.010464,
-.009571,-.010064,
-.010064,-.009571,
-.010464,-.009,
-.010759,-.008368,
-.010939,-.007695,
-.011,-.007,
-.011,.007,
-.010939,.007695,
-.010759,.008368,
-.010464,.009,
-.010064,.009571,
-.009571,.010064,
-.009,.010464,
-.008368,.010759,
-.007695,.010939,
-.007,.011,
.007,.011,
.007695,.010939,
.008368,.010759,
.009,.010464,
.009571,.010064,
.010064,.009571,
.010464,.009,
.010759,.008368,
.010939,.007695,
.011,.007,
.011,-.007,
.010939,-.007695,
.010759,-.008368,
.010464,-.009,
.010064,-.009571,
.009571,-.010064,
.009,-.010464,
.008368,-.010759,
.007695,-.010939,
.007,-.011,
0.0*
%
%ADD16MACRO16*%
%AMMACRO23*
4,1,44,.023,.00387,
.022901,.005261,
.022562,.006614,
.021993,.007887,
.021211,.009042,
.020241,.010044,
.019112,.010863,
.017857,.011472,
.016516,.011855,
.015129,.011999,
.015,.012,
-.015,.012,
-.016389,.011878,
-.017737,.011517,
-.019001,.010928,
-.020143,.010128,
-.021129,.009142,
-.021929,.007999,
-.022519,.006735,
-.022879,.005388,
-.023001,.003999,
-.023,.00387,
-.023,-.00387,
-.022901,-.005261,
-.022562,-.006614,
-.021993,-.007887,
-.021211,-.009042,
-.020241,-.010044,
-.019112,-.010863,
-.017857,-.011472,
-.016516,-.011855,
-.015129,-.011999,
-.015,-.012,
.015,-.012,
.016389,-.011878,
.017737,-.011517,
.019001,-.010928,
.020143,-.010128,
.021129,-.009142,
.021929,-.007999,
.022519,-.006735,
.022879,-.005388,
.023001,-.003999,
.023,-.00387,
.023,.00387,
0.0*
%
%ADD23MACRO23*%
%AMMACRO24*
4,1,40,-.013,.017,
.013,.017,
.013695,.016939,
.014368,.016759,
.015,.016464,
.015571,.016064,
.016064,.015571,
.016464,.015,
.016759,.014368,
.016939,.013695,
.017,.013,
.017,-.013,
.016939,-.013695,
.016759,-.014368,
.016464,-.015,
.016064,-.015571,
.015571,-.016064,
.015,-.016464,
.014368,-.016759,
.013695,-.016939,
.013,-.017,
-.013,-.017,
-.013695,-.016939,
-.014368,-.016759,
-.015,-.016464,
-.015571,-.016064,
-.016064,-.015571,
-.016464,-.015,
-.016759,-.014368,
-.016939,-.013695,
-.017,-.013,
-.017,.013,
-.016939,.013695,
-.016759,.014368,
-.016464,.015,
-.016064,.015571,
-.015571,.016064,
-.015,.016464,
-.014368,.016759,
-.013695,.016939,
-.013,.017,
0.0*
%
%ADD24MACRO24*%
%AMMACRO29*
4,1,40,-.011,-.007,
-.011,.007,
-.010939,.007695,
-.010759,.008368,
-.010464,.009,
-.010064,.009571,
-.009571,.010064,
-.009,.010464,
-.008368,.010759,
-.007695,.010939,
-.007,.011,
.007,.011,
.007695,.010939,
.008368,.010759,
.009,.010464,
.009571,.010064,
.010064,.009571,
.010464,.009,
.010759,.008368,
.010939,.007695,
.011,.007,
.011,-.007,
.010939,-.007695,
.010759,-.008368,
.010464,-.009,
.010064,-.009571,
.009571,-.010064,
.009,-.010464,
.008368,-.010759,
.007695,-.010939,
.007,-.011,
-.007,-.011,
-.007695,-.010939,
-.008368,-.010759,
-.009,-.010464,
-.009571,-.010064,
-.010064,-.009571,
-.010464,-.009,
-.010759,-.008368,
-.010939,-.007695,
-.011,-.007,
0.0*
%
%ADD29MACRO29*%
%AMMACRO17*
4,1,40,.007,-.011,
-.007,-.011,
-.007695,-.010939,
-.008368,-.010759,
-.009,-.010464,
-.009571,-.010064,
-.010064,-.009571,
-.010464,-.009,
-.010759,-.008368,
-.010939,-.007695,
-.011,-.007,
-.011,.007,
-.010939,.007695,
-.010759,.008368,
-.010464,.009,
-.010064,.009571,
-.009571,.010064,
-.009,.010464,
-.008368,.010759,
-.007695,.010939,
-.007,.011,
.007,.011,
.007695,.010939,
.008368,.010759,
.009,.010464,
.009571,.010064,
.010064,.009571,
.010464,.009,
.010759,.008368,
.010939,.007695,
.011,.007,
.011,-.007,
.010939,-.007695,
.010759,-.008368,
.010464,-.009,
.010064,-.009571,
.009571,-.010064,
.009,-.010464,
.008368,-.010759,
.007695,-.010939,
.007,-.011,
0.0*
%
%ADD17MACRO17*%
%AMMACRO25*
4,1,40,-.013,.017,
.013,.017,
.013695,.016939,
.014368,.016759,
.015,.016464,
.015571,.016064,
.016064,.015571,
.016464,.015,
.016759,.014368,
.016939,.013695,
.017,.013,
.017,-.013,
.016939,-.013695,
.016759,-.014368,
.016464,-.015,
.016064,-.015571,
.015571,-.016064,
.015,-.016464,
.014368,-.016759,
.013695,-.016939,
.013,-.017,
-.013,-.017,
-.013695,-.016939,
-.014368,-.016759,
-.015,-.016464,
-.015571,-.016064,
-.016064,-.015571,
-.016464,-.015,
-.016759,-.014368,
-.016939,-.013695,
-.017,-.013,
-.017,.013,
-.016939,.013695,
-.016759,.014368,
-.016464,.015,
-.016064,.015571,
-.015571,.016064,
-.015,.016464,
-.014368,.016759,
-.013695,.016939,
-.013,.017,
0.0*
%
%ADD25MACRO25*%
%ADD32R,.04X.022*%
%ADD20R,.032X.071*%
%ADD21R,.024X.063*%
%ADD22R,.016X.048*%
%AMMACRO31*
4,1,40,.008,-.012,
-.008,-.012,
-.008695,-.011939,
-.009368,-.011759,
-.01,-.011464,
-.010571,-.011064,
-.011064,-.010571,
-.011464,-.01,
-.011759,-.009368,
-.011939,-.008695,
-.012,-.008,
-.012,.008,
-.011939,.008695,
-.011759,.009368,
-.011464,.01,
-.011064,.010571,
-.010571,.011064,
-.01,.011464,
-.009368,.011759,
-.008695,.011939,
-.008,.012,
.008,.012,
.008695,.011939,
.009368,.011759,
.01,.011464,
.010571,.011064,
.011064,.010571,
.011464,.01,
.011759,.009368,
.011939,.008695,
.012,.008,
.012,-.008,
.011939,-.008695,
.011759,-.009368,
.011464,-.01,
.011064,-.010571,
.010571,-.011064,
.01,-.011464,
.009368,-.011759,
.008695,-.011939,
.008,-.012,
0.0*
%
%ADD31MACRO31*%
%AMMACRO18*
4,1,40,.011,.007,
.011,-.007,
.010939,-.007695,
.010759,-.008368,
.010464,-.009,
.010064,-.009571,
.009571,-.010064,
.009,-.010464,
.008368,-.010759,
.007695,-.010939,
.007,-.011,
-.007,-.011,
-.007695,-.010939,
-.008368,-.010759,
-.009,-.010464,
-.009571,-.010064,
-.010064,-.009571,
-.010464,-.009,
-.010759,-.008368,
-.010939,-.007695,
-.011,-.007,
-.011,.007,
-.010939,.007695,
-.010759,.008368,
-.010464,.009,
-.010064,.009571,
-.009571,.010064,
-.009,.010464,
-.008368,.010759,
-.007695,.010939,
-.007,.011,
.007,.011,
.007695,.010939,
.008368,.010759,
.009,.010464,
.009571,.010064,
.010064,.009571,
.010464,.009,
.010759,.008368,
.010939,.007695,
.011,.007,
0.0*
%
%ADD18MACRO18*%
%AMMACRO30*
4,1,40,.008,-.012,
-.008,-.012,
-.008695,-.011939,
-.009368,-.011759,
-.01,-.011464,
-.010571,-.011064,
-.011064,-.010571,
-.011464,-.01,
-.011759,-.009368,
-.011939,-.008695,
-.012,-.008,
-.012,.008,
-.011939,.008695,
-.011759,.009368,
-.011464,.01,
-.011064,.010571,
-.010571,.011064,
-.01,.011464,
-.009368,.011759,
-.008695,.011939,
-.008,.012,
.008,.012,
.008695,.011939,
.009368,.011759,
.01,.011464,
.010571,.011064,
.011064,.010571,
.011464,.01,
.011759,.009368,
.011939,.008695,
.012,.008,
.012,-.008,
.011939,-.008695,
.011759,-.009368,
.011464,-.01,
.011064,-.010571,
.010571,-.011064,
.01,-.011464,
.009368,-.011759,
.008695,-.011939,
.008,-.012,
0.0*
%
%ADD30MACRO30*%
%ADD33C,.016*%
%ADD34C,.006*%
%ADD35C,.007*%
%ADD36C,.008*%
%ADD43R,.019X.008*%
%ADD42C,.04404*%
%ADD41C,.09204*%
%ADD38C,.06604*%
%ADD37C,.11004*%
%ADD40R,.008X.008*%
%ADD39C,.197*%
G75*
%LPD*%
G75*
G36*
G01X3937Y3001D02*
G02X3001Y3937I0J936D01*
G01Y12207D01*
G02X3755Y12392I400J0D01*
G03Y26978I13962J7293D01*
G02X3001Y27163I-354J185D01*
G01Y57874D01*
G02X3937Y58810I936J0D01*
G01X30031D01*
G02X30265Y58086I0J-400D01*
G03X29471Y57266I1940J-2672D01*
G02X29205Y57205I-166J112D01*
G03X29309Y53460I-1105J-1905D01*
G02X29578Y53414I110J-167D01*
G03X34145Y58086I2627J2000D01*
G02X34379Y58810I234J324D01*
G01X48929D01*
G02X49163Y58086I0J-400D01*
G03X53949Y53739I1940J-2672D01*
G02X54556Y53838I345J-203D01*
G03X54498Y57110I1444J1662D01*
G02X53888Y57188I-273J293D01*
G03X53043Y58086I-2785J-1774D01*
G02X53277Y58810I234J324D01*
G01X65690D01*
X67500Y57000D01*
Y47000D01*
X61300Y40800D01*
X57100D01*
X55700Y39400D01*
Y34200D01*
X49500Y28000D01*
X45000D01*
X43500Y26500D01*
Y24500D01*
X46800Y21200D01*
Y3400D01*
X46401Y3001D01*
X3937D01*
G37*
G36*
G01X37417Y19685D02*
G03I-19700J0D01*
G37*
G36*
G01X98898Y12602D02*
X96500Y15000D01*
Y16500D01*
X97500Y17500D01*
X100000D01*
X102500Y20000D01*
X107000D01*
X108000Y19000D01*
Y13200D01*
X107402Y12602D01*
X98898D01*
G37*
G36*
G01X99199Y3001D02*
X98900Y3300D01*
Y9000D01*
X99200Y9300D01*
X107200D01*
X108000Y8500D01*
X110000D01*
X111500Y10000D01*
Y12000D01*
X109500Y14000D01*
Y19800D01*
X107800Y21500D01*
X105500D01*
X91500Y35500D01*
Y50500D01*
X92500Y51500D01*
X95500D01*
X96500Y50500D01*
Y42000D01*
X97600Y40900D01*
X101600D01*
X102000Y40500D01*
Y37800D01*
G03Y35000I1700J-1400D01*
G01Y31000D01*
X107000Y26000D01*
X107589D01*
X107612Y25994D01*
G03X108668I528J2138D01*
G01X108691Y26000D01*
X111500D01*
X112500Y25000D01*
Y22500D01*
X117000Y18000D01*
Y4500D01*
X115501Y3001D01*
X99199D01*
G37*
G36*
G01X84500Y19000D02*
X83500Y20000D01*
Y21500D01*
X87500Y25500D01*
Y34500D01*
X87000Y35000D01*
X83500D01*
X82500Y36000D01*
Y41000D01*
X82000Y41500D01*
X76500D01*
X73500Y38500D01*
Y37000D01*
X76500Y34000D01*
Y31000D01*
X75600Y30100D01*
X75265D01*
G03X75200Y30102I-82J-1599D01*
G01X73800D01*
G03X73735Y30100I17J-1601D01*
G01X65100D01*
X59500Y24500D01*
Y20500D01*
X58500Y19500D01*
X52000D01*
X51000Y20500D01*
Y23500D01*
X72400Y44900D01*
Y48700D01*
X73100Y49400D01*
X73235D01*
G03X73300Y49398I82J1599D01*
G01X74700D01*
G03X74765Y49400I-17J1601D01*
G01X81600D01*
X82500Y48500D01*
Y43500D01*
X83000Y43000D01*
X84500D01*
X86500Y41000D01*
Y38500D01*
X95500Y29500D01*
Y24500D01*
X97000Y23000D01*
X99500D01*
X100500Y22000D01*
Y20000D01*
X99500Y19000D01*
X84500D01*
G37*
G36*
G01X119500Y12000D02*
X118500Y13000D01*
Y16500D01*
X120500Y18500D01*
Y19810D01*
G03Y19990I-2200J90D01*
G01Y21000D01*
X119300Y22200D01*
X114500D01*
X113800Y22900D01*
Y26300D01*
X115000Y27500D01*
X124500D01*
X126000Y26000D01*
Y18000D01*
X124500Y16500D01*
Y13000D01*
X123500Y12000D01*
X119500D01*
G37*
G36*
G01X85000Y50400D02*
X84502Y50898D01*
Y55602D01*
X85400Y56500D01*
X88500D01*
X89500Y55500D01*
Y51500D01*
X88400Y50400D01*
X85000D01*
G37*
G36*
G01X138999Y3001D02*
X137500Y4500D01*
Y10000D01*
X135900Y11600D01*
X135599D01*
X135598Y11602D01*
X126498D01*
X126000Y12100D01*
Y16000D01*
X129000Y19000D01*
Y23500D01*
X134500Y29000D01*
Y57000D01*
X136310Y58810D01*
X173228D01*
G02X174164Y57874I0J-936D01*
G01Y27165D01*
G02X173410Y26980I-400J0D01*
G03Y12390I-13961J-7295D01*
G02X174164Y12205I354J-185D01*
G01Y3937D01*
G02X173228Y3001I-936J0D01*
G01X138999D01*
G37*
G36*
G01X179149Y19685D02*
G03I-19700J0D01*
G37*
G36*
G01X119999Y3001D02*
X118500Y4500D01*
Y9500D01*
X119400Y10400D01*
X126635D01*
G03X126700Y10398I82J1599D01*
G01X128300D01*
G03X128365Y10400I-17J1601D01*
G01X130135D01*
G03X130200Y10398I82J1599D01*
G01X131800D01*
G03X131865Y10400I-17J1601D01*
G01X135100D01*
X136000Y9500D01*
Y4500D01*
X134501Y3001D01*
X119999D01*
G37*
%LPC*%
G75*
G36*
G01X46000Y38300D02*
X47500Y36800D01*
Y34900D01*
X45600Y33000D01*
X38500D01*
X37000Y34500D01*
Y43000D01*
X35600Y44400D01*
X25900D01*
X24300Y46000D01*
Y48000D01*
X25800Y49500D01*
X58500D01*
X60000Y48000D01*
Y46000D01*
X58500Y44500D01*
X50500D01*
X46000Y40000D01*
Y38300D01*
G37*
G36*
G01X29643Y40871D02*
G03X29922Y40869I141J142D01*
G02X29183Y37154I2283J-2385D01*
G03X28925Y37258I-183J-81D01*
G02X29643Y40871I-825J2042D01*
G37*
G54D43*
X129250Y14000D03*
Y8000D03*
G54D42*
X133500Y15700D03*
G54D41*
X148500Y47500D03*
G54D38*
X51103Y38484D03*
G54D37*
X9000Y48000D03*
X164500Y48500D03*
G54D40*
X108500Y22400D03*
X73400Y32300D03*
X75600D03*
X75100Y47200D03*
X117500Y25800D03*
X126300Y8000D03*
X132200D03*
G54D39*
X17717Y19685D03*
X159449D03*
%LPD*%
G75*
G54D10*
X25827Y-9492D03*
X148500Y47500D03*
X519227Y-9492D03*
G54D20*
X40158Y16142D03*
X105512D03*
G54D11*
X17717Y19685D03*
X9000Y48000D03*
X26890Y46949D03*
X103642Y43898D03*
X56418Y46949D03*
X159449Y19685D03*
X164500Y48500D03*
X127264Y43898D03*
G54D30*
X127500Y9200D03*
X131000D03*
G54D21*
X45276Y6103D03*
X49213D03*
X53150D03*
X57087D03*
X61024D03*
X64961D03*
X68898D03*
X72835D03*
X76772D03*
X80709D03*
X84646D03*
X88583D03*
X92520D03*
X96457D03*
X100394D03*
G54D12*
X28802Y13285D03*
X24117Y8600D03*
X11317D03*
X6632Y13285D03*
Y26085D03*
X11317Y30770D03*
X24117D03*
X28802Y26085D03*
X170534Y13285D03*
X165849Y8600D03*
X153049D03*
X148364Y13285D03*
Y26085D03*
X153049Y30770D03*
X165849D03*
X170534Y26085D03*
G54D31*
X127500Y12800D03*
X131000D03*
G54D22*
X85060Y31250D03*
X82500D03*
X79940D03*
Y53250D03*
X82500D03*
X85060D03*
Y46750D03*
X79940D03*
Y37750D03*
X85060D03*
G54D13*
X32205Y38484D03*
Y55414D03*
X51103Y38484D03*
Y55414D03*
G54D32*
X132000Y21000D03*
X123000D03*
G54D23*
X113950Y11000D03*
X121050Y13560D03*
Y8440D03*
G54D14*
G01X-149983Y-76117D02*
Y-156117D01*
G01D02*
X864117D01*
G01X-153983Y-60117D02*
G02I-12000J0D01*
G01X-159133D02*
G02I-6850J0D01*
G01X-165983Y-76117D02*
Y-44117D01*
G01X-149983Y-60117D02*
X-181983D01*
G01X-149983Y-76117D02*
X864117D01*
G01X-149983Y-111617D02*
X864117D01*
G01X32205Y51912D02*
Y55414D01*
G01D02*
X35707D01*
G01X32205Y38484D02*
Y41986D01*
G01Y38484D02*
X35707D01*
G01X76617Y-76117D02*
Y-156117D01*
G01X70700Y11200D02*
X72835Y9065D01*
Y6103D01*
G01X107579Y52264D02*
X103655D01*
G01X51103Y51912D02*
Y55414D01*
G01X47601D02*
X51103D01*
G01Y34982D02*
Y38484D01*
G01D02*
Y41986D01*
G01X47601Y38484D02*
X51103D01*
G01D02*
X54605D01*
G01X123327Y52264D02*
X119403D01*
G01X214117Y-76117D02*
Y-156117D01*
G01X329117Y-76117D02*
Y-156117D01*
G01X496617Y-76117D02*
Y-156117D01*
G01X666617Y-76117D02*
Y-156117D01*
G01X864117Y-76117D02*
Y-156117D01*
G01X892117Y-60117D02*
G02I-12000J0D01*
G01X886967D02*
G02I-6850J0D01*
G01X880117Y-76117D02*
Y-44117D01*
G01X896117Y-60117D02*
X864117D01*
X28100Y39300D03*
X34200Y47000D03*
X28100Y55300D03*
X20000Y55000D03*
X15000Y45000D03*
X5000Y38000D03*
Y55000D03*
X30827Y47067D03*
X68750Y24100D03*
X79940Y26850D03*
X70700Y11200D03*
X40100Y21692D03*
X35000Y5000D03*
X41200Y7400D03*
X98200Y16500D03*
X108140Y28132D03*
X109000Y11000D03*
X95400Y12500D03*
X84100Y14900D03*
X81500Y12700D03*
X74200Y21700D03*
X53437Y13900D03*
X71405Y19607D03*
X68500Y13800D03*
X98000Y25500D03*
X69000Y17200D03*
X84700Y26702D03*
X65300Y24437D03*
X65800Y21000D03*
X54500Y25500D03*
X98700Y21000D03*
X95300D03*
X85100Y21100D03*
X56200Y21000D03*
X52800D03*
X45250Y35850D03*
X36733Y47067D03*
X44607Y46831D03*
X39400D03*
X52218Y47067D03*
X56000Y55500D03*
X103700Y36400D03*
X39300Y35500D03*
X47200Y47067D03*
X49730Y46821D03*
X87900Y53100D03*
X103655Y52264D03*
X61300Y47250D03*
X88940Y39400D03*
X76000Y37750D03*
X87700Y43400D03*
X94800Y46800D03*
X93000Y49700D03*
X58000Y38500D03*
X74000Y34900D03*
X119400Y29800D03*
X143000Y5000D03*
X137000Y12750D03*
X133500Y15700D03*
X118300Y19900D03*
X134200Y9000D03*
X131000Y6000D03*
X119500Y33900D03*
X170000Y45000D03*
X135500D03*
X155000D03*
X165000Y55000D03*
X145000D03*
Y36500D03*
X119403Y52264D03*
G54D33*
G01X79940Y31250D02*
Y26850D01*
G54D24*
X115800Y24100D03*
G54D15*
X115453Y35532D03*
X107579D03*
X99705D03*
X115453Y52264D03*
X107579D03*
X99705D03*
X123327Y35532D03*
X131201D03*
X123327Y52264D03*
X131201D03*
G54D34*
G01X-137600Y-128617D02*
Y-146117D01*
X-128866D01*
G01X-113987Y-136784D02*
X-113113Y-135909D01*
X-112458Y-134451D01*
X-112021Y-132408D01*
X-112458Y-130659D01*
X-113331Y-129492D01*
X-114860Y-128617D01*
X-120755D01*
Y-146117D01*
X-113550D01*
X-112021Y-144951D01*
X-111148Y-143200D01*
X-110711Y-141159D01*
X-111148Y-139117D01*
X-112458Y-137367D01*
X-113987Y-136784D01*
X-120755D01*
G01X-93430Y-130076D02*
X-94740Y-129200D01*
X-96268Y-128617D01*
X-98015D01*
X-99980Y-129492D01*
X-101508Y-130950D01*
X-102600Y-132701D01*
X-103473Y-135617D01*
X-103692Y-138242D01*
X-103255Y-140867D01*
X-102600Y-142617D01*
X-101290Y-144367D01*
X-99761Y-145534D01*
X-98233Y-146117D01*
X-96705D01*
X-95176Y-145534D01*
X-93866Y-144659D01*
X-92774Y-143493D01*
G01X-67600Y-128617D02*
Y-146117D01*
X-58866D01*
G01X-41366D02*
X-50100D01*
Y-128617D01*
X-41366D01*
G01X-44860Y-137075D02*
X-50100D01*
G01X-33036Y-146117D02*
Y-128617D01*
X-28670D01*
X-26923Y-129492D01*
X-25613Y-130659D01*
X-24521Y-132408D01*
X-23648Y-134451D01*
X-23430Y-137367D01*
X-23648Y-140284D01*
X-24521Y-142326D01*
X-25613Y-144076D01*
X-26923Y-145242D01*
X-28670Y-146117D01*
X-33036D01*
G01X10260Y-135909D02*
X8732Y-134742D01*
X7422Y-134451D01*
X5675Y-135034D01*
X4365Y-136200D01*
X3492Y-138242D01*
X3273Y-140284D01*
X3492Y-142326D01*
X4365Y-144076D01*
X5675Y-145534D01*
X7422Y-146117D01*
X8950Y-145534D01*
X10260Y-144367D01*
G01X28197Y-146117D02*
Y-134451D01*
G01Y-136492D02*
X27324Y-135326D01*
X26013Y-134742D01*
X24485Y-134451D01*
X22957Y-135034D01*
X21647Y-136200D01*
X20773Y-137950D01*
X20337Y-140284D01*
X20773Y-142617D01*
X21647Y-144367D01*
X22957Y-145534D01*
X24485Y-146117D01*
X26013Y-145825D01*
X27324Y-144951D01*
X28197Y-143784D01*
G01X38710Y-146117D02*
Y-134451D01*
G01Y-136784D02*
X39802Y-135617D01*
X40894Y-134742D01*
X42422Y-134451D01*
X43513Y-134742D01*
X44824Y-135617D01*
G01X63197Y-128617D02*
Y-146117D01*
G01Y-143493D02*
X62324Y-144951D01*
X61013Y-145825D01*
X59485Y-146117D01*
X57739Y-145534D01*
X56429Y-144076D01*
X55555Y-142326D01*
X55337Y-140284D01*
X55555Y-138242D01*
X56429Y-136492D01*
X57739Y-135034D01*
X59485Y-134451D01*
X61013Y-134742D01*
X62105Y-135326D01*
X63197Y-136492D01*
G01X-77660Y-101117D02*
Y-83617D01*
X-71983Y-98200D01*
X-66306Y-83617D01*
Y-101117D01*
G01X-54483D02*
X-55793Y-100825D01*
X-57103Y-99659D01*
X-57977Y-97617D01*
X-58413Y-95284D01*
X-57977Y-92950D01*
X-57103Y-90909D01*
X-55793Y-89742D01*
X-54483Y-89451D01*
X-53173Y-89742D01*
X-51863Y-90909D01*
X-50990Y-92950D01*
X-50771Y-95284D01*
X-50990Y-97617D01*
X-51863Y-99659D01*
X-53173Y-100825D01*
X-54483Y-101117D01*
G01X-33053Y-83617D02*
Y-101117D01*
G01Y-98493D02*
X-33926Y-99951D01*
X-35237Y-100825D01*
X-36765Y-101117D01*
X-38511Y-100534D01*
X-39821Y-99076D01*
X-40695Y-97326D01*
X-40913Y-95284D01*
X-40695Y-93242D01*
X-39821Y-91492D01*
X-38511Y-90034D01*
X-36765Y-89451D01*
X-35237Y-89742D01*
X-34145Y-90326D01*
X-33053Y-91492D01*
G01X-22758Y-93242D02*
X-15771D01*
X-16426Y-91200D01*
X-17518Y-90034D01*
X-19046Y-89451D01*
X-20575Y-89742D01*
X-21885Y-90617D01*
X-22758Y-92659D01*
X-23195Y-94409D01*
Y-96159D01*
X-22758Y-97909D01*
X-21666Y-99659D01*
X-20356Y-100825D01*
X-18828Y-101117D01*
X-17300Y-100534D01*
X-15771Y-98784D01*
G01X-1983Y-101117D02*
Y-83617D01*
G01X110317Y-146117D02*
Y-128617D01*
X107697Y-132117D01*
G01Y-146117D02*
X112937D01*
G01X123669Y-138826D02*
X125197Y-136784D01*
X126507Y-135617D01*
X128254Y-135034D01*
X129782Y-135617D01*
X130874Y-136784D01*
X131747Y-138534D01*
X131965Y-140575D01*
X131747Y-142326D01*
X130874Y-144076D01*
X129563Y-145534D01*
X128035Y-146117D01*
X126289Y-145534D01*
X124760Y-143784D01*
X123887Y-141159D01*
X123669Y-138242D01*
X124105Y-134451D01*
X124760Y-132408D01*
X125852Y-130367D01*
X127380Y-128909D01*
X128909Y-128617D01*
X130437Y-129200D01*
X131529Y-130659D01*
G01X140514Y-142617D02*
X141823Y-144659D01*
X143570Y-145825D01*
X145535Y-146117D01*
X147282Y-145825D01*
X149029Y-144367D01*
X150120Y-142617D01*
X150339Y-140867D01*
X149902Y-138826D01*
X148374Y-137367D01*
X146845Y-136784D01*
X144880D01*
G01X146845D02*
X148155Y-135909D01*
X149247Y-134451D01*
X149684Y-132701D01*
X149247Y-130950D01*
X148155Y-129492D01*
X146190Y-128617D01*
X144225Y-128909D01*
X142260Y-130076D01*
G01X158669Y-138826D02*
X160197Y-136784D01*
X161507Y-135617D01*
X163254Y-135034D01*
X164782Y-135617D01*
X165874Y-136784D01*
X166747Y-138534D01*
X166965Y-140575D01*
X166747Y-142326D01*
X165874Y-144076D01*
X164563Y-145534D01*
X163035Y-146117D01*
X161289Y-145534D01*
X159760Y-143784D01*
X158887Y-141159D01*
X158669Y-138242D01*
X159105Y-134451D01*
X159760Y-132408D01*
X160852Y-130367D01*
X162380Y-128909D01*
X163909Y-128617D01*
X165437Y-129200D01*
X166529Y-130659D01*
G01X180317Y-146117D02*
X181845Y-145825D01*
X183592Y-144951D01*
X184684Y-143493D01*
X185120Y-141450D01*
X184684Y-139409D01*
X183374Y-137659D01*
X181409Y-136784D01*
X179225D01*
X177915Y-136200D01*
X176823Y-134742D01*
X176387Y-132701D01*
X177042Y-130659D01*
X178570Y-129200D01*
X180317Y-128617D01*
X182063Y-129200D01*
X183592Y-130659D01*
X184247Y-132701D01*
X183810Y-134742D01*
X182719Y-136200D01*
X181409Y-136784D01*
X179225D01*
X177260Y-137659D01*
X175950Y-139409D01*
X175514Y-141450D01*
X175950Y-143493D01*
X177042Y-144951D01*
X178789Y-145825D01*
X180317Y-146117D01*
G01X97200Y-101117D02*
Y-83617D01*
X102440D01*
X104187Y-84492D01*
X105497Y-86534D01*
X105934Y-88867D01*
X105497Y-91200D01*
X104405Y-92950D01*
X102440Y-93826D01*
X97200D01*
G01X123870Y-85076D02*
X122560Y-84200D01*
X121032Y-83617D01*
X119285D01*
X117320Y-84492D01*
X115792Y-85950D01*
X114700Y-87701D01*
X113827Y-90617D01*
X113608Y-93242D01*
X114045Y-95867D01*
X114700Y-97617D01*
X116010Y-99367D01*
X117539Y-100534D01*
X119067Y-101117D01*
X120595D01*
X122124Y-100534D01*
X123434Y-99659D01*
X124526Y-98493D01*
G01X138313Y-91784D02*
X139187Y-90909D01*
X139842Y-89451D01*
X140279Y-87408D01*
X139842Y-85659D01*
X138969Y-84492D01*
X137440Y-83617D01*
X131545D01*
Y-101117D01*
X138750D01*
X140279Y-99951D01*
X141152Y-98200D01*
X141589Y-96159D01*
X141152Y-94117D01*
X139842Y-92367D01*
X138313Y-91784D01*
X131545D01*
G01X147517Y-106950D02*
X160617D01*
G01X166545Y-101117D02*
Y-83617D01*
X176589Y-101117D01*
Y-83617D01*
G01X189067Y-101117D02*
X187320Y-100825D01*
X185792Y-99659D01*
X184482Y-97909D01*
X183608Y-95867D01*
X183172Y-93534D01*
Y-91200D01*
X183608Y-88867D01*
X184482Y-86825D01*
X185792Y-85076D01*
X187320Y-83909D01*
X189067Y-83617D01*
X190813Y-83909D01*
X192342Y-85076D01*
X193652Y-86825D01*
X194526Y-88867D01*
X194962Y-91200D01*
Y-93534D01*
X194526Y-95867D01*
X193652Y-97909D01*
X192342Y-99659D01*
X190813Y-100825D01*
X189067Y-101117D01*
G01X258282Y-143784D02*
X260029Y-145242D01*
X261994Y-146117D01*
X263740D01*
X265487Y-145242D01*
X266797Y-143784D01*
X267452Y-141742D01*
X267015Y-139701D01*
X265924Y-137950D01*
X263959Y-136784D01*
X261339Y-136200D01*
X259810Y-135034D01*
X259155Y-132992D01*
X259592Y-130950D01*
X260684Y-129492D01*
X262212Y-128617D01*
X263740D01*
X265269Y-129200D01*
X266579Y-130659D01*
G01X282113Y-136784D02*
X282987Y-135909D01*
X283642Y-134451D01*
X284079Y-132408D01*
X283642Y-130659D01*
X282769Y-129492D01*
X281240Y-128617D01*
X275345D01*
Y-146117D01*
X282550D01*
X284079Y-144951D01*
X284952Y-143200D01*
X285389Y-141159D01*
X284952Y-139117D01*
X283642Y-137367D01*
X282113Y-136784D01*
X275345D01*
G01X239908Y-83617D02*
X245367Y-101117D01*
X250826Y-83617D01*
G01X267234Y-101117D02*
X258500D01*
Y-83617D01*
X267234D01*
G01X263740Y-92075D02*
X258500D01*
G01X276000Y-101117D02*
Y-83617D01*
X281459D01*
X283205Y-84492D01*
X284297Y-85659D01*
X284734Y-87992D01*
X284297Y-90326D01*
X282987Y-91784D01*
X281459Y-92659D01*
X276000D01*
G01X281459D02*
X284734Y-101117D01*
G01X297867Y-101700D02*
X297430Y-101409D01*
Y-100825D01*
X297867Y-100534D01*
X298304Y-100825D01*
Y-101409D01*
X297867Y-101700D01*
G01X425934Y-128617D02*
Y-146117D01*
X417200D01*
G01X408215Y-138826D02*
X406687Y-136784D01*
X405377Y-135617D01*
X403630Y-135034D01*
X402102Y-135617D01*
X401010Y-136784D01*
X400137Y-138534D01*
X399919Y-140575D01*
X400137Y-142326D01*
X401010Y-144076D01*
X402321Y-145534D01*
X403849Y-146117D01*
X405595Y-145534D01*
X407124Y-143784D01*
X407997Y-141159D01*
X408215Y-138242D01*
X407779Y-134451D01*
X407124Y-132408D01*
X406032Y-130367D01*
X404504Y-128909D01*
X402975Y-128617D01*
X401447Y-129200D01*
X400355Y-130659D01*
G01X373450Y-83617D02*
Y-101117D01*
X382184D01*
G01X399247D02*
Y-89451D01*
G01Y-91492D02*
X398374Y-90326D01*
X397063Y-89742D01*
X395535Y-89451D01*
X394007Y-90034D01*
X392697Y-91200D01*
X391823Y-92950D01*
X391387Y-95284D01*
X391823Y-97617D01*
X392697Y-99367D01*
X394007Y-100534D01*
X395535Y-101117D01*
X397063Y-100825D01*
X398374Y-99951D01*
X399247Y-98784D01*
G01X408232Y-106367D02*
X409542Y-106950D01*
X411289Y-106367D01*
X412380Y-105201D01*
X413254Y-103742D01*
X414563Y-99076D01*
X417402Y-89451D01*
G01X410415D02*
X414563Y-99076D01*
G01X427042Y-93242D02*
X434029D01*
X433374Y-91200D01*
X432282Y-90034D01*
X430754Y-89451D01*
X429225Y-89742D01*
X427915Y-90617D01*
X427042Y-92659D01*
X426605Y-94409D01*
Y-96159D01*
X427042Y-97909D01*
X428134Y-99659D01*
X429444Y-100825D01*
X430972Y-101117D01*
X432500Y-100534D01*
X434029Y-98784D01*
G01X444760Y-101117D02*
Y-89451D01*
G01Y-91784D02*
X445852Y-90617D01*
X446944Y-89742D01*
X448472Y-89451D01*
X449563Y-89742D01*
X450874Y-90617D01*
G01X515564Y-101117D02*
Y-83617D01*
X519930D01*
X521677Y-84492D01*
X522987Y-85659D01*
X524079Y-87408D01*
X524952Y-89451D01*
X525170Y-92367D01*
X524952Y-95284D01*
X524079Y-97326D01*
X522987Y-99076D01*
X521677Y-100242D01*
X519930Y-101117D01*
X515564D01*
G01X534592Y-93242D02*
X541579D01*
X540924Y-91200D01*
X539832Y-90034D01*
X538304Y-89451D01*
X536775Y-89742D01*
X535465Y-90617D01*
X534592Y-92659D01*
X534155Y-94409D01*
Y-96159D01*
X534592Y-97909D01*
X535684Y-99659D01*
X536994Y-100825D01*
X538522Y-101117D01*
X540050Y-100534D01*
X541579Y-98784D01*
G01X552092Y-99076D02*
X553184Y-100242D01*
X554712Y-101117D01*
X556022D01*
X557332Y-100534D01*
X558205Y-99659D01*
X558642Y-98493D01*
X558424Y-96742D01*
X557550Y-95867D01*
X553620Y-94117D01*
X552747Y-92075D01*
X553184Y-90617D01*
X554057Y-89742D01*
X555367Y-89451D01*
X556677Y-89742D01*
X557987Y-90617D01*
G01X572867Y-89451D02*
Y-101117D01*
G01Y-84784D02*
X572430Y-84492D01*
Y-83909D01*
X572867Y-83617D01*
X573304Y-83909D01*
Y-84492D01*
X572867Y-84784D01*
G01X587310Y-105492D02*
X588839Y-106659D01*
X590585Y-106950D01*
X592113Y-106659D01*
X593424Y-105201D01*
X594297Y-103159D01*
Y-89451D01*
G01Y-91784D02*
X593424Y-90617D01*
X592113Y-89742D01*
X590585Y-89451D01*
X588839Y-90034D01*
X587747Y-91200D01*
X586873Y-93242D01*
X586437Y-95284D01*
X586655Y-97034D01*
X587529Y-99076D01*
X588839Y-100534D01*
X590585Y-101117D01*
X591895Y-100825D01*
X593424Y-99659D01*
X594297Y-98493D01*
G01X604155Y-101117D02*
Y-89451D01*
G01Y-92367D02*
X605029Y-90909D01*
X606339Y-89742D01*
X608085Y-89451D01*
X609613Y-89742D01*
X610924Y-90909D01*
X611579Y-92950D01*
Y-101117D01*
G01X622092Y-93242D02*
X629079D01*
X628424Y-91200D01*
X627332Y-90034D01*
X625804Y-89451D01*
X624275Y-89742D01*
X622965Y-90617D01*
X622092Y-92659D01*
X621655Y-94409D01*
Y-96159D01*
X622092Y-97909D01*
X623184Y-99659D01*
X624494Y-100825D01*
X626022Y-101117D01*
X627550Y-100534D01*
X629079Y-98784D01*
G01X639810Y-101117D02*
Y-89451D01*
G01Y-91784D02*
X640902Y-90617D01*
X641994Y-89742D01*
X643522Y-89451D01*
X644613Y-89742D01*
X645924Y-90617D01*
G01X559969Y-128617D02*
X568265D01*
X559969Y-146117D01*
X568265D01*
G01X581617D02*
X579870Y-145825D01*
X578342Y-144659D01*
X577032Y-142909D01*
X576158Y-140867D01*
X575722Y-138534D01*
Y-136200D01*
X576158Y-133867D01*
X577032Y-131825D01*
X578342Y-130076D01*
X579870Y-128909D01*
X581617Y-128617D01*
X583363Y-128909D01*
X584892Y-130076D01*
X586202Y-131825D01*
X587076Y-133867D01*
X587512Y-136200D01*
Y-138534D01*
X587076Y-140867D01*
X586202Y-142909D01*
X584892Y-144659D01*
X583363Y-145825D01*
X581617Y-146117D01*
G01X603484D02*
X594750D01*
Y-128617D01*
X603484D01*
G01X599990Y-137075D02*
X594750D01*
G01X686567Y-128617D02*
X684820Y-129200D01*
X683510Y-130659D01*
X682637Y-132408D01*
X681982Y-134742D01*
X681764Y-137367D01*
X681982Y-139992D01*
X682637Y-142326D01*
X683510Y-144076D01*
X684820Y-145534D01*
X686567Y-146117D01*
X688313Y-145534D01*
X689624Y-144076D01*
X690497Y-142326D01*
X691152Y-139992D01*
X691370Y-137367D01*
X691152Y-134742D01*
X690497Y-132408D01*
X689624Y-130659D01*
X688313Y-129200D01*
X686567Y-128617D01*
G01X699919Y-131534D02*
X701229Y-129784D01*
X702757Y-128909D01*
X704504Y-128617D01*
X706687Y-129200D01*
X708215Y-130659D01*
X708652Y-132408D01*
X708434Y-134159D01*
X707560Y-135617D01*
X703194Y-138534D01*
X701229Y-140575D01*
X699919Y-143493D01*
X699482Y-146117D01*
X708652D01*
G01X717637Y-146700D02*
X725497Y-128617D01*
G01X739067D02*
X737320Y-129200D01*
X736010Y-130659D01*
X735137Y-132408D01*
X734482Y-134742D01*
X734264Y-137367D01*
X734482Y-139992D01*
X735137Y-142326D01*
X736010Y-144076D01*
X737320Y-145534D01*
X739067Y-146117D01*
X740813Y-145534D01*
X742124Y-144076D01*
X742997Y-142326D01*
X743652Y-139992D01*
X743870Y-137367D01*
X743652Y-134742D01*
X742997Y-132408D01*
X742124Y-130659D01*
X740813Y-129200D01*
X739067Y-128617D01*
G01X756130Y-146117D02*
X756567Y-142326D01*
X757222Y-139117D01*
X758095Y-136200D01*
X759187Y-132992D01*
X760934Y-128617D01*
X752200D01*
G01X770137Y-146700D02*
X777997Y-128617D01*
G01X787419Y-131534D02*
X788729Y-129784D01*
X790257Y-128909D01*
X792004Y-128617D01*
X794187Y-129200D01*
X795715Y-130659D01*
X796152Y-132408D01*
X795934Y-134159D01*
X795060Y-135617D01*
X790694Y-138534D01*
X788729Y-140575D01*
X787419Y-143493D01*
X786982Y-146117D01*
X796152D01*
G01X809067Y-128617D02*
X807320Y-129200D01*
X806010Y-130659D01*
X805137Y-132408D01*
X804482Y-134742D01*
X804264Y-137367D01*
X804482Y-139992D01*
X805137Y-142326D01*
X806010Y-144076D01*
X807320Y-145534D01*
X809067Y-146117D01*
X810813Y-145534D01*
X812124Y-144076D01*
X812997Y-142326D01*
X813652Y-139992D01*
X813870Y-137367D01*
X813652Y-134742D01*
X812997Y-132408D01*
X812124Y-130659D01*
X810813Y-129200D01*
X809067Y-128617D01*
G01X826567Y-146117D02*
Y-128617D01*
X823947Y-132117D01*
G01Y-146117D02*
X829187D01*
G01X843630D02*
X844067Y-142326D01*
X844722Y-139117D01*
X845595Y-136200D01*
X846687Y-132992D01*
X848434Y-128617D01*
X839700D01*
G01X734264Y-101117D02*
Y-83617D01*
X738630D01*
X740377Y-84492D01*
X741687Y-85659D01*
X742779Y-87408D01*
X743652Y-89451D01*
X743870Y-92367D01*
X743652Y-95284D01*
X742779Y-97326D01*
X741687Y-99076D01*
X740377Y-100242D01*
X738630Y-101117D01*
X734264D01*
G01X760497D02*
Y-89451D01*
G01Y-91492D02*
X759624Y-90326D01*
X758313Y-89742D01*
X756785Y-89451D01*
X755257Y-90034D01*
X753947Y-91200D01*
X753073Y-92950D01*
X752637Y-95284D01*
X753073Y-97617D01*
X753947Y-99367D01*
X755257Y-100534D01*
X756785Y-101117D01*
X758313Y-100825D01*
X759624Y-99951D01*
X760497Y-98784D01*
G01X774067Y-83617D02*
Y-101117D01*
G01X771010Y-89451D02*
X777124D01*
G01X788292Y-93242D02*
X795279D01*
X794624Y-91200D01*
X793532Y-90034D01*
X792004Y-89451D01*
X790475Y-89742D01*
X789165Y-90617D01*
X788292Y-92659D01*
X787855Y-94409D01*
Y-96159D01*
X788292Y-97909D01*
X789384Y-99659D01*
X790694Y-100825D01*
X792222Y-101117D01*
X793750Y-100534D01*
X795279Y-98784D01*
G54D25*
X110200Y24100D03*
G54D16*
X66900Y27500D03*
G54D35*
G01X115453Y52264D02*
X111800D01*
G01X96000Y55600D02*
Y53500D01*
X97236Y52264D01*
X99705D01*
G01X111700Y39600D02*
Y36600D01*
X112768Y35532D01*
X115453D01*
G01X103700Y36400D02*
X104568Y35532D01*
X107579D01*
G01X39300Y35500D02*
X47200Y43400D01*
Y47067D01*
G01X131201Y52264D02*
X127500D01*
G01X119500Y33900D02*
X121132Y35532D01*
X123327D01*
G01X127500Y37000D02*
X128968Y35532D01*
X131201D01*
G54D17*
X70300Y27500D03*
G54D26*
X46000Y25600D03*
X111800Y52264D03*
X96000Y55600D03*
X111700Y39600D03*
X127500Y52264D03*
Y37000D03*
G54D36*
G01X109000Y11000D02*
X97500D01*
X96457Y9957D01*
Y6103D01*
G01X95400Y12500D02*
X92520Y9620D01*
Y6103D01*
G01X84100Y14900D02*
X88583Y10417D01*
Y6103D01*
G01X81500Y12700D02*
X84646Y9554D01*
Y6103D01*
G01X74200Y21700D02*
Y16300D01*
X80709Y9791D01*
Y6103D01*
G01X71405Y19607D02*
Y15983D01*
X76772Y10616D01*
Y6103D01*
G01X68500Y13800D02*
Y6501D01*
X68898Y6103D01*
G01X69000Y17200D02*
X64961Y13161D01*
Y6103D01*
G01X84700Y26702D02*
Y25088D01*
X82262Y22650D01*
X76488D01*
X75438Y23700D01*
X72300D01*
X61024Y12424D01*
Y6103D01*
G01X65300Y24437D02*
X63800Y22937D01*
Y18312D01*
X57087Y11599D01*
Y6103D01*
G01X66850Y27500D02*
X65000D01*
X61600Y24100D01*
Y19224D01*
X53150Y10774D01*
Y6103D01*
G01X49213D02*
Y25213D01*
X63000Y39000D01*
G01X74500Y27750D02*
X77400Y24850D01*
X81350D01*
X82500Y26000D01*
Y31250D01*
G01X70350Y27500D02*
X72250D01*
X72500Y27750D01*
X74500D01*
G01X70000Y48250D02*
Y46000D01*
X63000Y39000D01*
G01X82500Y53250D02*
Y56000D01*
X81000Y57500D01*
X75300D01*
X74000Y56200D01*
G01Y51750D02*
Y56200D01*
G01X70000Y51750D02*
X74000D01*
G01X79940Y37750D02*
X76000D01*
G01X87700Y43400D02*
Y45700D01*
X86650Y46750D01*
X85060D01*
G54D18*
X74500Y27800D03*
X70000Y48300D03*
G54D27*
X113000Y19300D03*
X63000Y39000D03*
X74000Y56200D03*
X73500Y42000D03*
X156000Y53500D03*
G54D28*
X74000Y51700D03*
G54D19*
X74500Y31200D03*
X70000Y51700D03*
G54D29*
X74000Y48300D03*
M02*
